(kicad_pcb
	(version 20260206)
	(generator "pcbnew")
	(generator_version "10.0")
	(general
		(thickness 1.6)
		(legacy_teardrops no)
	)
	(paper "A4")
	(title_block
		(title "01162023_DA0F0TEBIF0_F0T_Expander_BD_F_brd_V02_OCP.brd")
		(comment 1 "Grand Teton / footprints 4685-4690 of 9728")
	)
	(layers
		(0 "F.Cu" signal "TOP")
		(4 "In1.Cu" signal "GND")
		(6 "In2.Cu" signal "VCC")
		(8 "In3.Cu" signal "VCC1")
		(10 "In4.Cu" signal "GND1")
		(12 "In5.Cu" signal "IN1")
		(14 "In6.Cu" signal "GND2")
		(16 "In7.Cu" signal "IN2")
		(18 "In8.Cu" signal "GND3")
		(20 "In9.Cu" signal "IN3")
		(22 "In10.Cu" signal "GND4")
		(24 "In11.Cu" signal "IN4")
		(26 "In12.Cu" signal "GND5")
		(28 "In13.Cu" signal "IN5")
		(30 "In14.Cu" signal "GND6")
		(32 "In15.Cu" signal "IN6")
		(34 "In16.Cu" signal "GND7")
		(2 "B.Cu" signal "BOTTOM")
		(9 "F.Adhes" user "F.Adhesive")
		(11 "B.Adhes" user "B.Adhesive")
		(13 "F.Paste" user "Package Geometry/Pastemask Top")
		(15 "B.Paste" user "Package Geometry/Pastemask Bottom")
		(5 "F.SilkS" user "Ref Des/Silkscreen Top")
		(7 "B.SilkS" user "Ref Des/Silkscreen Bottom")
		(1 "F.Mask" user "Board Geometry/Soldermask Top")
		(3 "B.Mask" user "Board Geometry/Soldermask Bottom")
		(17 "Dwgs.User" user "User.Drawings")
		(19 "Cmts.User" user "User.Comments")
		(21 "Eco1.User" user "User.Eco1")
		(23 "Eco2.User" user "User.Eco2")
		(25 "Edge.Cuts" user "Board Geometry/Outline")
		(27 "Margin" user)
		(31 "F.CrtYd" user "Package Geometry/Place Bound Top")
		(29 "B.CrtYd" user "Package Geometry/Place Bound Bottom")
		(35 "F.Fab" user "Ref Des/Assembly Top")
		(33 "B.Fab" user "Ref Des/Assembly Bottom")
	)
	(footprint ""
		(layer "F.Cu")
		(at 127.33401 -137.01776 180)
		(property "Reference" "PU26"
			(at 2.605024 -2.84226 0)
			(unlocked yes)
			(layer "F.SilkS")
			(effects
				(font
					(size 0.7874 0.5842)
					(thickness 0.1524)
				)
				(justify left)
			)
		)
		(property "Value" ""
			(at 0 0 180)
			(layer "F.Fab")
			(effects
				(font
					(size 1.27 1.27)
				)
			)
		)
		(duplicate_pad_numbers_are_jumpers no)
		(fp_line
			(start 1.943608 1.549908)
			(end -1.943608 1.549908)
			(stroke
				(width 0.1524)
				(type default)
			)
			(layer "F.SilkS")
		)
		(fp_line
			(start 1.943608 -1.549908)
			(end 1.943608 1.549908)
			(stroke
				(width 0.1524)
				(type default)
			)
			(layer "F.SilkS")
		)
		(fp_line
			(start -1.943608 1.549908)
			(end -1.943608 -1.549908)
			(stroke
				(width 0.1524)
				(type default)
			)
			(layer "F.SilkS")
		)
		(fp_line
			(start -1.943608 -1.549908)
			(end 1.943608 -1.549908)
			(stroke
				(width 0.1524)
				(type default)
			)
			(layer "F.SilkS")
		)
		(fp_poly
			(pts
				(xy -2.019808 -1.549908) (xy -1.257808 -1.549908) (xy -1.257808 -1.880108) (xy -2.019808 -1.880108)
			)
			(stroke
				(width 0)
				(type default)
			)
			(fill yes)
			(layer "F.SilkS")
		)
		(fp_line
			(start 1.549908 1.549908)
			(end -1.549908 1.549908)
			(stroke
				(width 0.1)
				(type default)
			)
			(layer "F.Fab")
		)
		(fp_line
			(start 1.549908 -1.549908)
			(end 1.549908 1.549908)
			(stroke
				(width 0.1)
				(type default)
			)
			(layer "F.Fab")
		)
		(fp_line
			(start -1.549908 1.549908)
			(end -1.549908 -1.549908)
			(stroke
				(width 0.1)
				(type default)
			)
			(layer "F.Fab")
		)
		(fp_line
			(start -1.549908 -1.549908)
			(end 1.549908 -1.549908)
			(stroke
				(width 0.1)
				(type default)
			)
			(layer "F.Fab")
		)
		(fp_poly
			(pts
				(xy -2.019808 -1.549908) (xy -1.257808 -1.549908) (xy -1.257808 -1.880108) (xy -2.019808 -1.880108)
			)
			(stroke
				(width 0)
				(type default)
			)
			(fill yes)
			(layer "F.Fab")
		)
		(pad "1" smd rect
			(at -1.500124 -1.249934 90)
			(size 0.2794 0.6096)
			(layers "F.Cu" "F.Mask" "F.Paste")
			(net "P12V_NIC2_R")
		)
		(pad "2" smd rect
			(at -1.500124 -0.750062 90)
			(size 0.2794 0.6096)
			(layers "F.Cu" "F.Mask" "F.Paste")
			(net "P12V_NIC2_R")
		)
		(pad "3" smd rect
			(at -1.500124 -0.249936 90)
			(size 0.2794 0.6096)
			(layers "F.Cu" "F.Mask" "F.Paste")
			(net "P12V_NIC2_R")
		)
		(pad "4" smd rect
			(at -1.500124 0.249936 90)
			(size 0.2794 0.6096)
			(layers "F.Cu" "F.Mask" "F.Paste")
			(net "P12V_NIC2_R")
		)
		(pad "5" smd rect
			(at -1.500124 0.750062 90)
			(size 0.2794 0.6096)
			(layers "F.Cu" "F.Mask" "F.Paste")
			(net "P12V_NIC2_R")
		)
		(pad "6" smd rect
			(at -1.500124 1.249934 90)
			(size 0.2794 0.6096)
			(layers "F.Cu" "F.Mask" "F.Paste")
			(net "GND")
		)
		(pad "7" smd rect
			(at 1.500124 1.249934 90)
			(size 0.2794 0.6096)
			(layers "F.Cu" "F.Mask" "F.Paste")
			(net "P12V_NIC2_SS")
		)
		(pad "8" smd rect
			(at 1.500124 0.750062 90)
			(size 0.2794 0.6096)
			(layers "F.Cu" "F.Mask" "F.Paste")
			(net "PWRGD_P12V_NIC2")
		)
		(pad "9" smd rect
			(at 1.500124 0.249936 90)
			(size 0.2794 0.6096)
			(layers "F.Cu" "F.Mask" "F.Paste")
			(net "P12V_NIC2_OCP")
		)
		(pad "10" smd rect
			(at 1.500124 -0.249936 90)
			(size 0.2794 0.6096)
			(layers "F.Cu" "F.Mask" "F.Paste")
			(net "P5V_AUX")
		)
		(pad "11" smd rect
			(at 1.500124 -0.750062 90)
			(size 0.2794 0.6096)
			(layers "F.Cu" "F.Mask" "F.Paste")
			(net "P12V_NIC2_EN_R")
		)
		(pad "12" smd rect
			(at 1.500124 -1.249934 90)
			(size 0.2794 0.6096)
			(layers "F.Cu" "F.Mask" "F.Paste")
			(net "P12V_AUX")
		)
		(pad "13" smd rect
			(at 0 0 180)
			(size 1.9812 2.7178)
			(layers "F.Cu" "F.Mask" "F.Paste")
			(net "P12V_AUX")
		)
		(zone
			(layer "F.Cu")
			(hatch none 0.5)
			(connect_pads
				(clearance 0)
			)
			(min_thickness 0.25)
			(keepout
				(tracks not_allowed)
				(vias allowed)
				(pads allowed)
				(copperpour not_allowed)
				(footprints allowed)
			)
			(placement
				(enabled no)
				(sheetname "")
			)
			(fill
				(thermal_gap 0.5)
				(thermal_bridge_width 0.5)
				(island_removal_mode 0)
			)
			(polygon
				(pts
					(xy 126.19101 -135.46836) (xy 126.19101 -135.59536) (xy 126.19101 -138.56716) (xy 126.19101 -138.567668)
					(xy 128.47701 -138.567668) (xy 128.47701 -138.56716) (xy 128.47701 -138.44016) (xy 128.47701 -137.01776)
					(xy 128.37541 -137.01776) (xy 128.37541 -138.44016) (xy 126.29261 -138.44016) (xy 126.29261 -135.59536)
					(xy 128.37541 -135.59536) (xy 128.37541 -136.99236) (xy 128.47701 -136.99236) (xy 128.47701 -135.59536)
					(xy 128.47701 -135.46836) (xy 128.47701 -135.467852) (xy 126.19101 -135.467852)
				)
			)
		)
	)
	(footprint ""
		(layer "F.Cu")
		(at 250.1265 -25.432004 -90)
		(property "Reference" "C973"
			(at 0 0 270)
			(layer "F.SilkS")
			(hide yes)
			(effects
				(font
					(size 1.27 1.27)
				)
			)
		)
		(property "Value" ""
			(at 0 0 270)
			(layer "F.Fab")
			(effects
				(font
					(size 1.27 1.27)
				)
			)
		)
		(duplicate_pad_numbers_are_jumpers no)
		(fp_line
			(start -0.7874 0.4064)
			(end -0.7874 -0.4064)
			(stroke
				(width 0.1524)
				(type default)
			)
			(layer "F.SilkS")
		)
		(fp_line
			(start 0.7874 0.4064)
			(end -0.7874 0.4064)
			(stroke
				(width 0.1524)
				(type default)
			)
			(layer "F.SilkS")
		)
		(fp_line
			(start -0.7874 -0.4064)
			(end 0.7874 -0.4064)
			(stroke
				(width 0.1524)
				(type default)
			)
			(layer "F.SilkS")
		)
		(fp_line
			(start 0.7874 -0.4064)
			(end 0.7874 0.4064)
			(stroke
				(width 0.1524)
				(type default)
			)
			(layer "F.SilkS")
		)
		(fp_line
			(start -0.67945 0.3048)
			(end -0.67945 -0.305054)
			(stroke
				(width 0.1)
				(type default)
			)
			(layer "F.Fab")
		)
		(fp_line
			(start -0.12065 0.3048)
			(end -0.67945 0.3048)
			(stroke
				(width 0.1)
				(type default)
			)
			(layer "F.Fab")
		)
		(fp_line
			(start 0.120396 0.3048)
			(end 0.120396 0.2794)
			(stroke
				(width 0.1)
				(type default)
			)
			(layer "F.Fab")
		)
		(fp_line
			(start 0.67945 0.3048)
			(end 0.120396 0.3048)
			(stroke
				(width 0.1)
				(type default)
			)
			(layer "F.Fab")
		)
		(fp_line
			(start -0.12065 0.2794)
			(end -0.12065 0.3048)
			(stroke
				(width 0.1)
				(type default)
			)
			(layer "F.Fab")
		)
		(fp_line
			(start 0.120396 0.2794)
			(end -0.12065 0.2794)
			(stroke
				(width 0.1)
				(type default)
			)
			(layer "F.Fab")
		)
		(fp_line
			(start -0.12065 -0.2794)
			(end 0.12065 -0.2794)
			(stroke
				(width 0.1)
				(type default)
			)
			(layer "F.Fab")
		)
		(fp_line
			(start 0.12065 -0.2794)
			(end 0.12065 -0.3048)
			(stroke
				(width 0.1)
				(type default)
			)
			(layer "F.Fab")
		)
		(fp_line
			(start 0.12065 -0.3048)
			(end 0.67945 -0.3048)
			(stroke
				(width 0.1)
				(type default)
			)
			(layer "F.Fab")
		)
		(fp_line
			(start 0.67945 -0.3048)
			(end 0.67945 0.3048)
			(stroke
				(width 0.1)
				(type default)
			)
			(layer "F.Fab")
		)
		(fp_line
			(start -0.67945 -0.305054)
			(end -0.12065 -0.305054)
			(stroke
				(width 0.1)
				(type default)
			)
			(layer "F.Fab")
		)
		(fp_line
			(start -0.12065 -0.305054)
			(end -0.12065 -0.2794)
			(stroke
				(width 0.1)
				(type default)
			)
			(layer "F.Fab")
		)
		(pad "1" smd circle
			(at -0.40005 0 270)
			(size 0 0)
			(layers "F.Cu" "F.Mask" "F.Paste")
			(net "GND")
		)
		(pad "2" smd circle
			(at 0.40005 0 270)
			(size 0 0)
			(layers "F.Cu" "F.Mask" "F.Paste")
			(net "P3V3_SSD8")
		)
	)
	(footprint ""
		(layer "F.Cu")
		(at 356.182422 -279.486868 -90)
		(property "Reference" "PR159"
			(at 0 0 270)
			(layer "F.SilkS")
			(hide yes)
			(effects
				(font
					(size 1.27 1.27)
				)
			)
		)
		(property "Value" ""
			(at 0 0 270)
			(layer "F.Fab")
			(effects
				(font
					(size 1.27 1.27)
				)
			)
		)
		(duplicate_pad_numbers_are_jumpers no)
		(fp_line
			(start -0.7874 0.4064)
			(end -0.7874 -0.4064)
			(stroke
				(width 0.1524)
				(type default)
			)
			(layer "F.SilkS")
		)
		(fp_line
			(start 0.7874 0.4064)
			(end -0.7874 0.4064)
			(stroke
				(width 0.1524)
				(type default)
			)
			(layer "F.SilkS")
		)
		(fp_line
			(start -0.7874 -0.4064)
			(end 0.7874 -0.4064)
			(stroke
				(width 0.1524)
				(type default)
			)
			(layer "F.SilkS")
		)
		(fp_line
			(start 0.7874 -0.4064)
			(end 0.7874 0.4064)
			(stroke
				(width 0.1524)
				(type default)
			)
			(layer "F.SilkS")
		)
		(fp_line
			(start -0.67945 0.3048)
			(end -0.67945 -0.305054)
			(stroke
				(width 0.1)
				(type default)
			)
			(layer "F.Fab")
		)
		(fp_line
			(start -0.12065 0.3048)
			(end -0.67945 0.3048)
			(stroke
				(width 0.1)
				(type default)
			)
			(layer "F.Fab")
		)
		(fp_line
			(start 0.120396 0.3048)
			(end 0.120396 0.2794)
			(stroke
				(width 0.1)
				(type default)
			)
			(layer "F.Fab")
		)
		(fp_line
			(start 0.67945 0.3048)
			(end 0.120396 0.3048)
			(stroke
				(width 0.1)
				(type default)
			)
			(layer "F.Fab")
		)
		(fp_line
			(start -0.12065 0.2794)
			(end -0.12065 0.3048)
			(stroke
				(width 0.1)
				(type default)
			)
			(layer "F.Fab")
		)
		(fp_line
			(start 0.120396 0.2794)
			(end -0.12065 0.2794)
			(stroke
				(width 0.1)
				(type default)
			)
			(layer "F.Fab")
		)
		(fp_line
			(start -0.12065 -0.2794)
			(end 0.12065 -0.2794)
			(stroke
				(width 0.1)
				(type default)
			)
			(layer "F.Fab")
		)
		(fp_line
			(start 0.12065 -0.2794)
			(end 0.12065 -0.3048)
			(stroke
				(width 0.1)
				(type default)
			)
			(layer "F.Fab")
		)
		(fp_line
			(start 0.12065 -0.3048)
			(end 0.67945 -0.3048)
			(stroke
				(width 0.1)
				(type default)
			)
			(layer "F.Fab")
		)
		(fp_line
			(start 0.67945 -0.3048)
			(end 0.67945 0.3048)
			(stroke
				(width 0.1)
				(type default)
			)
			(layer "F.Fab")
		)
		(fp_line
			(start -0.67945 -0.305054)
			(end -0.12065 -0.305054)
			(stroke
				(width 0.1)
				(type default)
			)
			(layer "F.Fab")
		)
		(fp_line
			(start -0.12065 -0.305054)
			(end -0.12065 -0.2794)
			(stroke
				(width 0.1)
				(type default)
			)
			(layer "F.Fab")
		)
		(pad "1" smd circle
			(at -0.40005 0 270)
			(size 0 0)
			(layers "F.Cu" "F.Mask" "F.Paste")
			(net "P0V8_PEX3_LSET1")
		)
		(pad "2" smd circle
			(at 0.40005 0 270)
			(size 0 0)
			(layers "F.Cu" "F.Mask" "F.Paste")
			(net "GND")
		)
	)
	(footprint ""
		(layer "F.Cu")
		(at 347.481652 -303.649634 90)
		(property "Reference" "PC167"
			(at 0 0 90)
			(layer "F.SilkS")
			(hide yes)
			(effects
				(font
					(size 1.27 1.27)
				)
			)
		)
		(property "Value" ""
			(at 0 0 90)
			(layer "F.Fab")
			(effects
				(font
					(size 1.27 1.27)
				)
			)
		)
		(duplicate_pad_numbers_are_jumpers no)
		(fp_line
			(start 1.524 -0.762)
			(end 1.524 0.762)
			(stroke
				(width 0.1524)
				(type default)
			)
			(layer "F.SilkS")
		)
		(fp_line
			(start -1.524 -0.762)
			(end 1.524 -0.762)
			(stroke
				(width 0.1524)
				(type default)
			)
			(layer "F.SilkS")
		)
		(fp_line
			(start 1.524 0.762)
			(end -1.524 0.762)
			(stroke
				(width 0.1524)
				(type default)
			)
			(layer "F.SilkS")
		)
		(fp_line
			(start -1.524 0.762)
			(end -1.524 -0.762)
			(stroke
				(width 0.1524)
				(type default)
			)
			(layer "F.SilkS")
		)
		(fp_line
			(start 1.1049 -0.724916)
			(end -1.1049 -0.724916)
			(stroke
				(width 0.1)
				(type default)
			)
			(layer "F.Fab")
		)
		(fp_line
			(start -1.1049 -0.724916)
			(end -1.1049 0.724916)
			(stroke
				(width 0.1)
				(type default)
			)
			(layer "F.Fab")
		)
		(fp_line
			(start 1.1049 0.724916)
			(end 1.1049 -0.724916)
			(stroke
				(width 0.1)
				(type default)
			)
			(layer "F.Fab")
		)
		(fp_line
			(start -1.1049 0.724916)
			(end 1.1049 0.724916)
			(stroke
				(width 0.1)
				(type default)
			)
			(layer "F.Fab")
		)
		(pad "1" smd rect
			(at -0.889 0 270)
			(size 1.016 1.27)
			(layers "F.Cu" "F.Mask" "F.Paste")
			(net "P0V8_PEX2")
		)
		(pad "2" smd rect
			(at 0.889 0 270)
			(size 1.016 1.27)
			(layers "F.Cu" "F.Mask" "F.Paste")
			(net "GND")
		)
	)
	(footprint ""
		(layer "F.Cu")
		(at 409.157932 -386.54101 90)
		(property "Reference" "C4162"
			(at 0 0 90)
			(layer "F.SilkS")
			(hide yes)
			(effects
				(font
					(size 1.27 1.27)
				)
			)
		)
		(property "Value" ""
			(at 0 0 90)
			(layer "F.Fab")
			(effects
				(font
					(size 1.27 1.27)
				)
			)
		)
		(duplicate_pad_numbers_are_jumpers no)
		(fp_line
			(start 0.7874 -0.4064)
			(end 0.7874 0.4064)
			(stroke
				(width 0.1524)
				(type default)
			)
			(layer "F.SilkS")
		)
		(fp_line
			(start -0.7874 -0.4064)
			(end 0.7874 -0.4064)
			(stroke
				(width 0.1524)
				(type default)
			)
			(layer "F.SilkS")
		)
		(fp_line
			(start 0.7874 0.4064)
			(end -0.7874 0.4064)
			(stroke
				(width 0.1524)
				(type default)
			)
			(layer "F.SilkS")
		)
		(fp_line
			(start -0.7874 0.4064)
			(end -0.7874 -0.4064)
			(stroke
				(width 0.1524)
				(type default)
			)
			(layer "F.SilkS")
		)
		(fp_line
			(start -0.12065 -0.305054)
			(end -0.12065 -0.2794)
			(stroke
				(width 0.1)
				(type default)
			)
			(layer "F.Fab")
		)
		(fp_line
			(start -0.67945 -0.305054)
			(end -0.12065 -0.305054)
			(stroke
				(width 0.1)
				(type default)
			)
			(layer "F.Fab")
		)
		(fp_line
			(start 0.67945 -0.3048)
			(end 0.67945 0.3048)
			(stroke
				(width 0.1)
				(type default)
			)
			(layer "F.Fab")
		)
		(fp_line
			(start 0.12065 -0.3048)
			(end 0.67945 -0.3048)
			(stroke
				(width 0.1)
				(type default)
			)
			(layer "F.Fab")
		)
		(fp_line
			(start 0.12065 -0.2794)
			(end 0.12065 -0.3048)
			(stroke
				(width 0.1)
				(type default)
			)
			(layer "F.Fab")
		)
		(fp_line
			(start -0.12065 -0.2794)
			(end 0.12065 -0.2794)
			(stroke
				(width 0.1)
				(type default)
			)
			(layer "F.Fab")
		)
		(fp_line
			(start 0.120396 0.2794)
			(end -0.12065 0.2794)
			(stroke
				(width 0.1)
				(type default)
			)
			(layer "F.Fab")
		)
		(fp_line
			(start -0.12065 0.2794)
			(end -0.12065 0.3048)
			(stroke
				(width 0.1)
				(type default)
			)
			(layer "F.Fab")
		)
		(fp_line
			(start 0.67945 0.3048)
			(end 0.120396 0.3048)
			(stroke
				(width 0.1)
				(type default)
			)
			(layer "F.Fab")
		)
		(fp_line
			(start 0.120396 0.3048)
			(end 0.120396 0.2794)
			(stroke
				(width 0.1)
				(type default)
			)
			(layer "F.Fab")
		)
		(fp_line
			(start -0.12065 0.3048)
			(end -0.67945 0.3048)
			(stroke
				(width 0.1)
				(type default)
			)
			(layer "F.Fab")
		)
		(fp_line
			(start -0.67945 0.3048)
			(end -0.67945 -0.305054)
			(stroke
				(width 0.1)
				(type default)
			)
			(layer "F.Fab")
		)
		(pad "1" smd circle
			(at -0.40005 0 90)
			(size 0 0)
			(layers "F.Cu" "F.Mask" "F.Paste")
			(net "GND")
		)
		(pad "2" smd circle
			(at 0.40005 0 90)
			(size 0 0)
			(layers "F.Cu" "F.Mask" "F.Paste")
			(net "GPU_3V3IO_RSVD4")
		)
	)
	(footprint ""
		(layer "F.Cu")
		(at 351.288096 -293.816786 -90)
		(property "Reference" "PC180"
			(at 0 0 270)
			(layer "F.SilkS")
			(hide yes)
			(effects
				(font
					(size 1.27 1.27)
				)
			)
		)
		(property "Value" ""
			(at 0 0 270)
			(layer "F.Fab")
			(effects
				(font
					(size 1.27 1.27)
				)
			)
		)
		(duplicate_pad_numbers_are_jumpers no)
		(fp_line
			(start -0.7874 0.4064)
			(end -0.7874 -0.4064)
			(stroke
				(width 0.1524)
				(type default)
			)
			(layer "F.SilkS")
		)
		(fp_line
			(start 0.7874 0.4064)
			(end -0.7874 0.4064)
			(stroke
				(width 0.1524)
				(type default)
			)
			(layer "F.SilkS")
		)
		(fp_line
			(start -0.7874 -0.4064)
			(end 0.7874 -0.4064)
			(stroke
				(width 0.1524)
				(type default)
			)
			(layer "F.SilkS")
		)
		(fp_line
			(start 0.7874 -0.4064)
			(end 0.7874 0.4064)
			(stroke
				(width 0.1524)
				(type default)
			)
			(layer "F.SilkS")
		)
		(fp_line
			(start -0.67945 0.3048)
			(end -0.67945 -0.305054)
			(stroke
				(width 0.1)
				(type default)
			)
			(layer "F.Fab")
		)
		(fp_line
			(start -0.12065 0.3048)
			(end -0.67945 0.3048)
			(stroke
				(width 0.1)
				(type default)
			)
			(layer "F.Fab")
		)
		(fp_line
			(start 0.120396 0.3048)
			(end 0.120396 0.2794)
			(stroke
				(width 0.1)
				(type default)
			)
			(layer "F.Fab")
		)
		(fp_line
			(start 0.67945 0.3048)
			(end 0.120396 0.3048)
			(stroke
				(width 0.1)
				(type default)
			)
			(layer "F.Fab")
		)
		(fp_line
			(start -0.12065 0.2794)
			(end -0.12065 0.3048)
			(stroke
				(width 0.1)
				(type default)
			)
			(layer "F.Fab")
		)
		(fp_line
			(start 0.120396 0.2794)
			(end -0.12065 0.2794)
			(stroke
				(width 0.1)
				(type default)
			)
			(layer "F.Fab")
		)
		(fp_line
			(start -0.12065 -0.2794)
			(end 0.12065 -0.2794)
			(stroke
				(width 0.1)
				(type default)
			)
			(layer "F.Fab")
		)
		(fp_line
			(start 0.12065 -0.2794)
			(end 0.12065 -0.3048)
			(stroke
				(width 0.1)
				(type default)
			)
			(layer "F.Fab")
		)
		(fp_line
			(start 0.12065 -0.3048)
			(end 0.67945 -0.3048)
			(stroke
				(width 0.1)
				(type default)
			)
			(layer "F.Fab")
		)
		(fp_line
			(start 0.67945 -0.3048)
			(end 0.67945 0.3048)
			(stroke
				(width 0.1)
				(type default)
			)
			(layer "F.Fab")
		)
		(fp_line
			(start -0.67945 -0.305054)
			(end -0.12065 -0.305054)
			(stroke
				(width 0.1)
				(type default)
			)
			(layer "F.Fab")
		)
		(fp_line
			(start -0.12065 -0.305054)
			(end -0.12065 -0.2794)
			(stroke
				(width 0.1)
				(type default)
			)
			(layer "F.Fab")
		)
		(pad "1" smd circle
			(at -0.40005 0 270)
			(size 0 0)
			(layers "F.Cu" "F.Mask" "F.Paste")
			(net "P0V8_PEX3")
		)
		(pad "2" smd circle
			(at 0.40005 0 270)
			(size 0 0)
			(layers "F.Cu" "F.Mask" "F.Paste")
			(net "GND")
		)
	)
)
